(kicad_pcb
	(version 20241229)
	(generator "pcbnew")
	(generator_version "9.0")
	(general
		(thickness 1.62)
		(legacy_teardrops no)
	)
	(paper "A3")
	(title_block
		(title "COM Express 7 Baseboard")
		(date "2025-02-04")
		(rev "1.1.2")
		(company "Antmicro Ltd")
		(comment 1 "www.antmicro.com")
		(comment 9 "footprints 196-199 of 802")
	)
	(layers
		(0 "F.Cu" signal)
		(4 "In1.Cu" signal)
		(6 "In2.Cu" signal)
		(8 "In3.Cu" signal)
		(10 "In4.Cu" signal)
		(12 "In5.Cu" signal)
		(14 "In6.Cu" signal)
		(2 "B.Cu" signal)
		(9 "F.Adhes" user "F.Adhesive")
		(11 "B.Adhes" user "B.Adhesive")
		(13 "F.Paste" user)
		(15 "B.Paste" user)
		(5 "F.SilkS" user "F.Silkscreen")
		(7 "B.SilkS" user "B.Silkscreen")
		(1 "F.Mask" user)
		(3 "B.Mask" user)
		(17 "Dwgs.User" user "User.Drawings")
		(19 "Cmts.User" user "User.Comments")
		(21 "Eco1.User" user "User.Eco1")
		(23 "Eco2.User" user "User.Eco2")
		(25 "Edge.Cuts" user)
		(27 "Margin" user)
		(31 "F.CrtYd" user "F.Courtyard")
		(29 "B.CrtYd" user "B.Courtyard")
		(35 "F.Fab" user)
		(33 "B.Fab" user)
	)
	(footprint "antmicro-footprints:USON-10_2.5x1mm_P0.5mm"
		(layer "F.Cu")
		(at 112.15 132.41)
		(descr "USON-10 2.5x1mm_ Pitch 0.5mm")
		(tags "USON-10 2.5x1mm Pitch 0.5mm")
		(property "Reference" "U47"
			(at 1.75 1.25 90)
			(layer "F.SilkS")
			(effects
				(font
					(size 0.7 0.7)
					(thickness 0.15)
				)
				(justify left bottom)
			)
		)
		(property "Value" "ESD204DQAR"
			(at 0.018 2.499 0)
			(layer "F.Fab")
			(effects
				(font
					(size 0.7 0.7)
					(thickness 0.15)
				)
				(justify left bottom)
			)
		)
		(property "Datasheet" "https://www.ti.com/lit/ds/symlink/esd204.pdf?ts=1706004844383&ref_url=https%253A%252F%252Fwww.ti.com%252Finterface%252Fdiodes%252Fesd-protection-diodes%252Fproducts.html"
			(at 0 0 0)
			(layer "F.Fab")
			(hide yes)
			(effects
				(font
					(size 1.27 1.27)
					(thickness 0.15)
				)
			)
		)
		(property "Author" "Antmicro"
			(at 0 0 0)
			(layer "F.Fab")
			(hide yes)
			(effects
				(font
					(size 1 1)
					(thickness 0.15)
				)
			)
		)
		(property "License" "Apache-2.0"
			(at 0 0 0)
			(layer "F.Fab")
			(hide yes)
			(effects
				(font
					(size 1 1)
					(thickness 0.15)
				)
			)
		)
		(property "MPN" "ESD204DQAR"
			(at 0 0 0)
			(layer "F.Fab")
			(hide yes)
			(effects
				(font
					(size 1 1)
					(thickness 0.15)
				)
			)
		)
		(property "Manufacturer" "Texas Instruments"
			(at 0 0 0)
			(layer "F.Fab")
			(hide yes)
			(effects
				(font
					(size 1 1)
					(thickness 0.15)
				)
			)
		)
		(sheetname "SD card")
		(sheetfile "sd_card.kicad_sch")
		(attr smd)
		(fp_line
			(start 0.498 -1.401)
			(end -0.5 -1.401)
			(stroke
				(width 0.15)
				(type solid)
			)
			(layer "F.SilkS")
		)
		(fp_line
			(start 0.498 1.398)
			(end -0.5 1.398)
			(stroke
				(width 0.15)
				(type solid)
			)
			(layer "F.SilkS")
		)
		(fp_circle
			(center -0.68 -1.27)
			(end -0.63 -1.27)
			(stroke
				(width 0.15)
				(type solid)
			)
			(fill yes)
			(layer "F.SilkS")
		)
		(fp_rect
			(start -0.8 -1.5)
			(end 0.8 1.499)
			(stroke
				(width 0.05)
				(type solid)
			)
			(fill no)
			(layer "F.CrtYd")
		)
		(fp_line
			(start -0.5 -1)
			(end -0.5 1.249)
			(stroke
				(width 0.15)
				(type solid)
			)
			(layer "F.Fab")
		)
		(fp_line
			(start -0.5 1.249)
			(end 0.498 1.249)
			(stroke
				(width 0.15)
				(type solid)
			)
			(layer "F.Fab")
		)
		(fp_line
			(start -0.25 -1.25)
			(end -0.5 -1)
			(stroke
				(width 0.15)
				(type solid)
			)
			(layer "F.Fab")
		)
		(fp_line
			(start 0.498 -1.25)
			(end -0.25 -1.25)
			(stroke
				(width 0.15)
				(type solid)
			)
			(layer "F.Fab")
		)
		(fp_line
			(start 0.498 -1.25)
			(end 0.498 1.249)
			(stroke
				(width 0.15)
				(type solid)
			)
			(layer "F.Fab")
		)
		(pad "1" smd roundrect
			(at -0.387 -1 270)
			(size 0.25 0.55)
			(layers "F.Cu" "F.Mask" "F.Paste")
			(roundrect_rratio 0.25)
			(net 531 "/Com Express 7 Interfaces/SD_CD")
			(pintype "passive")
			(teardrops
				(best_length_ratio 0.2)
				(max_length 1)
				(best_width_ratio 0.9)
				(max_width 2)
				(curved_edges yes)
				(filter_ratio 0.9)
				(enabled yes)
				(allow_two_segments yes)
				(prefer_zone_connections yes)
			)
		)
		(pad "2" smd roundrect
			(at -0.387 -0.5 270)
			(size 0.25 0.55)
			(layers "F.Cu" "F.Mask" "F.Paste")
			(roundrect_rratio 0.25)
			(net 322 "/Com Express 7 Interfaces/SDIO.DAT1")
			(pintype "passive")
			(teardrops
				(best_length_ratio 0.2)
				(max_length 1)
				(best_width_ratio 0.9)
				(max_width 2)
				(curved_edges yes)
				(filter_ratio 0.9)
				(enabled yes)
				(allow_two_segments yes)
				(prefer_zone_connections yes)
			)
		)
		(pad "3" smd roundrect
			(at -0.387 0 270)
			(size 0.4 0.55)
			(layers "F.Cu" "F.Mask" "F.Paste")
			(roundrect_rratio 0.25)
			(net 1 "GND")
			(pintype "power_in")
			(teardrops
				(best_length_ratio 0.2)
				(max_length 1)
				(best_width_ratio 0.9)
				(max_width 2)
				(curved_edges yes)
				(filter_ratio 0.9)
				(enabled yes)
				(allow_two_segments yes)
				(prefer_zone_connections yes)
			)
		)
		(pad "4" smd roundrect
			(at -0.387 0.498 270)
			(size 0.25 0.55)
			(layers "F.Cu" "F.Mask" "F.Paste")
			(roundrect_rratio 0.25)
			(net 321 "/Com Express 7 Interfaces/SDIO.DAT0")
			(pintype "passive")
			(teardrops
				(best_length_ratio 0.2)
				(max_length 1)
				(best_width_ratio 0.9)
				(max_width 2)
				(curved_edges yes)
				(filter_ratio 0.9)
				(enabled yes)
				(allow_two_segments yes)
				(prefer_zone_connections yes)
			)
		)
		(pad "5" smd roundrect
			(at -0.387 0.998 270)
			(size 0.25 0.55)
			(layers "F.Cu" "F.Mask" "F.Paste")
			(roundrect_rratio 0.25)
			(net 339 "/Com Express 7 Interfaces/SDIO.CLK")
			(pintype "passive")
			(teardrops
				(best_length_ratio 0.2)
				(max_length 1)
				(best_width_ratio 0.9)
				(max_width 2)
				(curved_edges yes)
				(filter_ratio 0.9)
				(enabled yes)
				(allow_two_segments yes)
				(prefer_zone_connections yes)
			)
		)
		(pad "6" smd roundrect
			(at 0.385 0.998 270)
			(size 0.25 0.55)
			(layers "F.Cu" "F.Mask" "F.Paste")
			(roundrect_rratio 0.25)
			(net 339 "/Com Express 7 Interfaces/SDIO.CLK")
			(pintype "passive")
			(teardrops
				(best_length_ratio 0.2)
				(max_length 1)
				(best_width_ratio 0.9)
				(max_width 2)
				(curved_edges yes)
				(filter_ratio 0.9)
				(enabled yes)
				(allow_two_segments yes)
				(prefer_zone_connections yes)
			)
		)
		(pad "7" smd roundrect
			(at 0.385 0.498 270)
			(size 0.25 0.55)
			(layers "F.Cu" "F.Mask" "F.Paste")
			(roundrect_rratio 0.25)
			(net 321 "/Com Express 7 Interfaces/SDIO.DAT0")
			(pintype "passive")
			(teardrops
				(best_length_ratio 0.2)
				(max_length 1)
				(best_width_ratio 0.9)
				(max_width 2)
				(curved_edges yes)
				(filter_ratio 0.9)
				(enabled yes)
				(allow_two_segments yes)
				(prefer_zone_connections yes)
			)
		)
		(pad "8" smd roundrect
			(at 0.385 0 270)
			(size 0.4 0.55)
			(layers "F.Cu" "F.Mask" "F.Paste")
			(roundrect_rratio 0.25)
			(net 1 "GND")
			(pintype "passive")
			(teardrops
				(best_length_ratio 0.2)
				(max_length 1)
				(best_width_ratio 0.9)
				(max_width 2)
				(curved_edges yes)
				(filter_ratio 0.9)
				(enabled yes)
				(allow_two_segments yes)
				(prefer_zone_connections yes)
			)
		)
		(pad "9" smd roundrect
			(at 0.385 -0.5 270)
			(size 0.25 0.55)
			(layers "F.Cu" "F.Mask" "F.Paste")
			(roundrect_rratio 0.25)
			(net 322 "/Com Express 7 Interfaces/SDIO.DAT1")
			(pintype "passive")
			(teardrops
				(best_length_ratio 0.2)
				(max_length 1)
				(best_width_ratio 0.9)
				(max_width 2)
				(curved_edges yes)
				(filter_ratio 0.9)
				(enabled yes)
				(allow_two_segments yes)
				(prefer_zone_connections yes)
			)
		)
		(pad "10" smd roundrect
			(at 0.385 -1 270)
			(size 0.25 0.55)
			(layers "F.Cu" "F.Mask" "F.Paste")
			(roundrect_rratio 0.25)
			(net 531 "/Com Express 7 Interfaces/SD_CD")
			(pintype "passive")
			(teardrops
				(best_length_ratio 0.2)
				(max_length 1)
				(best_width_ratio 0.9)
				(max_width 2)
				(curved_edges yes)
				(filter_ratio 0.9)
				(enabled yes)
				(allow_two_segments yes)
				(prefer_zone_connections yes)
			)
		)
	)
	(footprint "antmicro-footprints:R_0402_1005Metric"
		(layer "F.Cu")
		(at 302.95 84.01 -90)
		(descr "Resistor SMD 0402")
		(tags "resistor SMD 0402")
		(property "Reference" "R130"
			(at -1.35 0.5 90)
			(layer "F.SilkS")
			(effects
				(font
					(size 0.7 0.7)
					(thickness 0.15)
				)
				(justify right bottom)
			)
		)
		(property "Value" "R_0R_0402"
			(at -1.011843 1.772047 90)
			(layer "F.Fab")
			(effects
				(font
					(size 0.7 0.7)
					(thickness 0.15)
				)
				(justify right bottom)
			)
		)
		(property "Datasheet" "https://industrial.panasonic.com/cdbs/www-data/pdf/RDA0000/AOA0000C301.pdf"
			(at 0 0 270)
			(layer "F.Fab")
			(hide yes)
			(effects
				(font
					(size 1.27 1.27)
					(thickness 0.15)
				)
			)
		)
		(property "Author" "Antmicro"
			(at 218.94 386.96 0)
			(layer "F.Fab")
			(hide yes)
			(effects
				(font
					(size 1 1)
					(thickness 0.15)
				)
			)
		)
		(property "Current" "1A"
			(at 218.94 386.96 0)
			(layer "F.Fab")
			(hide yes)
			(effects
				(font
					(size 1 1)
					(thickness 0.15)
				)
			)
		)
		(property "License" "Apache-2.0"
			(at 218.94 386.96 0)
			(layer "F.Fab")
			(hide yes)
			(effects
				(font
					(size 1 1)
					(thickness 0.15)
				)
			)
		)
		(property "MPN" "ERJ2GE0R00X"
			(at 218.94 386.96 0)
			(layer "F.Fab")
			(hide yes)
			(effects
				(font
					(size 1 1)
					(thickness 0.15)
				)
			)
		)
		(property "Manufacturer" "Panasonic"
			(at 218.94 386.96 0)
			(layer "F.Fab")
			(hide yes)
			(effects
				(font
					(size 1 1)
					(thickness 0.15)
				)
			)
		)
		(property "Public" "False"
			(at 218.94 386.96 0)
			(layer "F.Fab")
			(hide yes)
			(effects
				(font
					(size 1 1)
					(thickness 0.15)
				)
			)
		)
		(property "Tolerance" ""
			(at 218.94 386.96 0)
			(layer "F.Fab")
			(hide yes)
			(effects
				(font
					(size 1 1)
					(thickness 0.15)
				)
			)
		)
		(property "Val" "0R"
			(at 218.94 386.96 0)
			(layer "F.Fab")
			(hide yes)
			(effects
				(font
					(size 1 1)
					(thickness 0.15)
				)
			)
		)
		(sheetname "M.2 key M #2")
		(sheetfile "m2keym.kicad_sch")
		(attr smd)
		(fp_rect
			(start -0.925 -0.47)
			(end 0.925 0.47)
			(stroke
				(width 0.05)
				(type default)
			)
			(fill no)
			(layer "F.CrtYd")
		)
		(fp_rect
			(start -0.5 -0.25)
			(end 0.5 0.25)
			(stroke
				(width 0.15)
				(type solid)
			)
			(fill no)
			(layer "F.Fab")
		)
		(pad "1" smd roundrect
			(at -0.48 0 270)
			(size 0.59 0.64)
			(layers "F.Cu" "F.Mask" "F.Paste")
			(roundrect_rratio 0.25)
			(net 277 "Net-(J8-SUSCLK)")
			(pintype "passive")
			(teardrops
				(best_length_ratio 0.2)
				(max_length 1)
				(best_width_ratio 0.9)
				(max_width 2)
				(curved_edges yes)
				(filter_ratio 0.9)
				(enabled yes)
				(allow_two_segments yes)
				(prefer_zone_connections yes)
			)
		)
		(pad "2" smd roundrect
			(at 0.48 0 270)
			(size 0.59 0.64)
			(layers "F.Cu" "F.Mask" "F.Paste")
			(roundrect_rratio 0.25)
			(net 587 "/M.2 key E/SUSCLK")
			(pintype "passive")
			(teardrops
				(best_length_ratio 0.2)
				(max_length 1)
				(best_width_ratio 0.9)
				(max_width 2)
				(curved_edges yes)
				(filter_ratio 0.9)
				(enabled yes)
				(allow_two_segments yes)
				(prefer_zone_connections yes)
			)
		)
	)
	(footprint "antmicro-footprints:TP_SMD_0.75mm"
		(layer "F.Cu")
		(at 197.70861 72.802163 -90)
		(property "Reference" "TP98"
			(at 0 -0.6 90)
			(layer "F.SilkS")
			(hide yes)
			(effects
				(font
					(size 0.7 0.7)
					(thickness 0.15)
				)
				(justify right bottom)
			)
		)
		(property "Value" "TP_0.75mm_SMD"
			(at 0 1.2 90)
			(layer "F.Fab")
			(effects
				(font
					(size 0.7 0.7)
					(thickness 0.15)
				)
				(justify right bottom)
			)
		)
		(property "Author" "Antmicro"
			(at 124.906447 270.510773 0)
			(layer "F.Fab")
			(hide yes)
			(effects
				(font
					(size 1 1)
					(thickness 0.15)
				)
			)
		)
		(property "License" "Apache-2.0"
			(at 124.906447 270.510773 0)
			(layer "F.Fab")
			(hide yes)
			(effects
				(font
					(size 1 1)
					(thickness 0.15)
				)
			)
		)
		(property "MPN" ""
			(at 124.906447 270.510773 0)
			(layer "F.Fab")
			(hide yes)
			(effects
				(font
					(size 1 1)
					(thickness 0.15)
				)
			)
		)
		(property "Manufacturer" ""
			(at 124.906447 270.510773 0)
			(layer "F.Fab")
			(hide yes)
			(effects
				(font
					(size 1 1)
					(thickness 0.15)
				)
			)
		)
		(property "Public" "False"
			(at 124.906447 270.510773 0)
			(layer "F.Fab")
			(hide yes)
			(effects
				(font
					(size 1 1)
					(thickness 0.15)
				)
			)
		)
		(sheetname "Power")
		(sheetfile "power.kicad_sch")
		(attr exclude_from_pos_files exclude_from_bom)
		(fp_circle
			(center 0 0)
			(end 0.475 0)
			(stroke
				(width 0.05)
				(type default)
			)
			(fill no)
			(layer "F.CrtYd")
		)
		(pad "1" smd circle
			(at 0 0 270)
			(size 0.75 0.75)
			(layers "F.Cu" "F.Mask")
			(net 2 "+3V3")
			(pinfunction "1")
			(pintype "passive")
			(teardrops
				(best_length_ratio 0.4)
				(max_length 1)
				(best_width_ratio 0.9)
				(max_width 2)
				(curved_edges yes)
				(filter_ratio 0.9)
				(enabled yes)
				(allow_two_segments yes)
				(prefer_zone_connections yes)
			)
		)
	)
	(footprint "antmicro-footprints:C_0402_1005Metric"
		(layer "F.Cu")
		(at 118.9 146.301 90)
		(descr "Capacitor SMD 0402")
		(tags "capacitor SMD 0402")
		(property "Reference" "C120"
			(at 10.541 1.1 90)
			(layer "F.SilkS")
			(effects
				(font
					(size 0.7 0.7)
					(thickness 0.15)
				)
				(justify left bottom)
			)
		)
		(property "Value" "C_100n_0402"
			(at -1.022927 2.155213 90)
			(layer "F.Fab")
			(effects
				(font
					(size 0.7 0.7)
					(thickness 0.15)
				)
				(justify left bottom)
			)
		)
		(property "Datasheet" "https://www.murata.com/products/productdetail?partno=GRM155R61H104KE14%23"
			(at 0 0 90)
			(layer "F.Fab")
			(hide yes)
			(effects
				(font
					(size 1.27 1.27)
					(thickness 0.15)
				)
			)
		)
		(property "Author" "Antmicro"
			(at 265.201 27.401 0)
			(layer "F.Fab")
			(hide yes)
			(effects
				(font
					(size 1 1)
					(thickness 0.15)
				)
			)
		)
		(property "Dielectric" "X5R"
			(at 265.201 27.401 0)
			(layer "F.Fab")
			(hide yes)
			(effects
				(font
					(size 1 1)
					(thickness 0.15)
				)
			)
		)
		(property "License" "Apache-2.0"
			(at 265.201 27.401 0)
			(layer "F.Fab")
			(hide yes)
			(effects
				(font
					(size 1 1)
					(thickness 0.15)
				)
			)
		)
		(property "MPN" "GRM155R61H104KE14D"
			(at 265.201 27.401 0)
			(layer "F.Fab")
			(hide yes)
			(effects
				(font
					(size 1 1)
					(thickness 0.15)
				)
			)
		)
		(property "Manufacturer" "Murata"
			(at 265.201 27.401 0)
			(layer "F.Fab")
			(hide yes)
			(effects
				(font
					(size 1 1)
					(thickness 0.15)
				)
			)
		)
		(property "Public" "False"
			(at 265.201 27.401 0)
			(layer "F.Fab")
			(hide yes)
			(effects
				(font
					(size 1 1)
					(thickness 0.15)
				)
			)
		)
		(property "Val" "100n"
			(at 265.201 27.401 0)
			(layer "F.Fab")
			(hide yes)
			(effects
				(font
					(size 1 1)
					(thickness 0.15)
				)
			)
		)
		(property "Voltage" "50V"
			(at 265.201 27.401 0)
			(layer "F.Fab")
			(hide yes)
			(effects
				(font
					(size 1 1)
					(thickness 0.15)
				)
			)
		)
		(sheetname "PCIe redriver")
		(sheetfile "pcie_redriver.kicad_sch")
		(attr smd)
		(fp_rect
			(start -0.925 -0.47)
			(end 0.925 0.47)
			(stroke
				(width 0.05)
				(type default)
			)
			(fill no)
			(layer "F.CrtYd")
		)
		(fp_line
			(start 0.504 -0.25)
			(end 0.504 0.248)
			(stroke
				(width 0.15)
				(type solid)
			)
			(layer "F.Fab")
		)
		(fp_line
			(start -0.494 -0.25)
			(end 0.504 -0.25)
			(stroke
				(width 0.15)
				(type solid)
			)
			(layer "F.Fab")
		)
		(fp_line
			(start 0.504 0.248)
			(end -0.494 0.248)
			(stroke
				(width 0.15)
				(type solid)
			)
			(layer "F.Fab")
		)
		(fp_line
			(start -0.494 0.248)
			(end -0.494 -0.25)
			(stroke
				(width 0.15)
				(type solid)
			)
			(layer "F.Fab")
		)
		(pad "1" smd roundrect
			(at -0.48 0 90)
			(size 0.59 0.64)
			(layers "F.Cu" "F.Mask" "F.Paste")
			(roundrect_rratio 0.25)
			(net 1 "GND")
			(pintype "passive")
			(teardrops
				(best_length_ratio 0.2)
				(max_length 1)
				(best_width_ratio 0.9)
				(max_width 2)
				(curved_edges yes)
				(filter_ratio 0.9)
				(enabled yes)
				(allow_two_segments yes)
				(prefer_zone_connections yes)
			)
		)
		(pad "2" smd roundrect
			(at 0.48 0 90)
			(size 0.59 0.64)
			(layers "F.Cu" "F.Mask" "F.Paste")
			(roundrect_rratio 0.25)
			(net 2 "+3V3")
			(pintype "passive")
			(teardrops
				(best_length_ratio 0.2)
				(max_length 1)
				(best_width_ratio 0.9)
				(max_width 2)
				(curved_edges yes)
				(filter_ratio 0.9)
				(enabled yes)
				(allow_two_segments yes)
				(prefer_zone_connections yes)
			)
		)
	)
)
